(kicad_pcb
	(version 20221018)
	(generator pcbnew)
	(general
    (thickness 1.562)
  )
	(paper "A4")
	(title_block
    (title "Thunderbolt PCIe Adaper")
    (date "2024-07-09")
    (rev "1.0.3")
    (comment 1 "www.antmicro.com")
    (comment 2 "Antmicro Ltd.")
		(comment 9 "footprints 51-52 of 271")
	)
	(layers
    (0 "F.Cu" signal)
    (1 "In1.Cu" signal)
    (2 "In2.Cu" signal)
    (3 "In3.Cu" signal)
    (4 "In4.Cu" signal)
    (31 "B.Cu" signal)
    (32 "B.Adhes" user "B.Adhesive")
    (33 "F.Adhes" user "F.Adhesive")
    (34 "B.Paste" user)
    (35 "F.Paste" user)
    (36 "B.SilkS" user "B.Silkscreen")
    (37 "F.SilkS" user "F.Silkscreen")
    (38 "B.Mask" user)
    (39 "F.Mask" user)
    (40 "Dwgs.User" user "User.Drawings")
    (41 "Cmts.User" user "User.Comments")
    (42 "Eco1.User" user "User.Eco1")
    (43 "Eco2.User" user "User.Eco2")
    (44 "Edge.Cuts" user)
    (45 "Margin" user)
    (46 "B.CrtYd" user "B.Courtyard")
    (47 "F.CrtYd" user "F.Courtyard")
    (48 "B.Fab" user)
    (49 "F.Fab" user)
  )
	(footprint "antmicro-footprints:L_Vishay-IHLP1616BZ" (layer "F.Cu")
    (at 139.8 70.8 90)
    (property "Author" "Antmicro")
    (property "IMax" "7.6 A")
    (property "ISat" "6.8 A")
    (property "License" "Apache-2.0")
    (property "MPN" "IHLP1616BZERR68M5A")
    (property "Manufacturer" "Vishay")
    (property "Sheetfile" "tb-power.kicad_sch")
    (property "Sheetname" "Thunderbolt Controller - Power")
    (property "Size" "4.06x4.06")
    (property "Val" "680n/7.6A")
    (property "ki_description" "Power Inductor (SMT), 680 nH, 7.6 A, Shielded, 6.8 A, IHLP-1616BZ-5A")
    (property "ki_keywords" "SMT, INDUCTOR, PASSIVE")
    (attr smd)
    (fp_text reference "L3" (at -0.447 -2.597 90) (layer "F.SilkS")
        (effects (font (size 0.7 0.7) (thickness 0.15)) (justify left bottom))
    )
    (fp_text value "L_680n_7.6A_IHLP1616BZ" (at -0.016 3.253 90) (layer "F.Fab")
        (effects (font (size 0.7 0.7) (thickness 0.15)) (justify left bottom))
    )
    (fp_text user "License: Apache-2.0" (at -3.07 6.453 90) (layer "F.Fab") hide
        (effects (font (size 0.7 0.7) (thickness 0.15)) (justify left bottom))
    )
    (fp_text user "${REFERENCE}" (at -3.07 7.653 90) (layer "F.Fab") hide
        (effects (font (size 0.7 0.7) (thickness 0.15)) (justify left bottom))
    )
    (fp_text user "Author: Antmicro" (at -3.07 5.253 90) (layer "F.Fab") hide
        (effects (font (size 0.7 0.7) (thickness 0.15)) (justify left bottom))
    )
    (fp_line (start -2.044 -2.024) (end -2.044 -1.45)
      (stroke (width 0.15) (type solid)) (layer "F.SilkS"))
    (fp_line (start -2.044 2.031) (end -2.044 1.45)
      (stroke (width 0.15) (type solid)) (layer "F.SilkS"))
    (fp_line (start -2.044 2.031) (end 2.012 2.031)
      (stroke (width 0.15) (type solid)) (layer "F.SilkS"))
    (fp_line (start 2.012 -2.024) (end -2.044 -2.024)
      (stroke (width 0.15) (type solid)) (layer "F.SilkS"))
    (fp_line (start 2.012 -2.024) (end 2.012 -1.45)
      (stroke (width 0.15) (type solid)) (layer "F.SilkS"))
    (fp_line (start 2.012 2.031) (end 2.012 1.45)
      (stroke (width 0.15) (type solid)) (layer "F.SilkS"))
    (fp_line (start -3.07 1.4) (end -3.07 -1.4)
      (stroke (width 0.05) (type solid)) (layer "F.CrtYd"))
    (fp_line (start -2.475 -2.31) (end 2.475 -2.31)
      (stroke (width 0.05) (type solid)) (layer "F.CrtYd"))
    (fp_line (start -2.475 -1.4) (end -3.07 -1.4)
      (stroke (width 0.05) (type solid)) (layer "F.CrtYd"))
    (fp_line (start -2.475 -1.4) (end -2.475 -2.31)
      (stroke (width 0.05) (type solid)) (layer "F.CrtYd"))
    (fp_line (start -2.475 1.4) (end -3.07 1.4)
      (stroke (width 0.05) (type solid)) (layer "F.CrtYd"))
    (fp_line (start -2.475 1.4) (end -2.475 2.32)
      (stroke (width 0.05) (type solid)) (layer "F.CrtYd"))
    (fp_line (start -2.475 2.32) (end 2.475 2.32)
      (stroke (width 0.05) (type solid)) (layer "F.CrtYd"))
    (fp_line (start 2.475 -1.4) (end 2.475 -2.31)
      (stroke (width 0.05) (type solid)) (layer "F.CrtYd"))
    (fp_line (start 2.475 -1.4) (end 3.07 -1.4)
      (stroke (width 0.05) (type solid)) (layer "F.CrtYd"))
    (fp_line (start 2.475 1.4) (end 2.475 2.32)
      (stroke (width 0.05) (type solid)) (layer "F.CrtYd"))
    (fp_line (start 2.475 1.4) (end 3.07 1.4)
      (stroke (width 0.05) (type solid)) (layer "F.CrtYd"))
    (fp_line (start 3.07 1.4) (end 3.07 -1.4)
      (stroke (width 0.05) (type solid)) (layer "F.CrtYd"))
    (fp_rect (start -2.217 -2.065) (end 2.217 2.064)
      (stroke (width 0.15) (type solid)) (fill none) (layer "F.Fab"))
    (pad "1" smd roundrect (at -1.89225 0 180) (size 2.286 1.8545) (layers "F.Cu" "F.Paste" "F.Mask") (roundrect_rratio 0.1)
      (net 55 "Net-(L3-Pad1)") (pintype "passive"))
    (pad "2" smd roundrect (at 1.89225 0 180) (size 2.286 1.8545) (layers "F.Cu" "F.Paste" "F.Mask") (roundrect_rratio 0.1)
      (net 112 "Net-(U4A-VCC0P9_SVR_SENSE)") (pintype "passive"))
  )
	(footprint "antmicro-footprints:PCIE_TE_2-2387405-2" (layer "F.Cu")
    (at 128 100.776)
    (property "Author" "Antmicro")
    (property "License" "Apache-2.0")
    (property "MPN" "2-2387405-2")
    (property "Manufacturer" "TE Connectivity")
    (property "Sheetfile" "connectors.kicad_sch")
    (property "Sheetname" "Connectors")
    (property "ki_description" "64 Position Female Connector PCI Express™ Gold 0.039\" (1.00mm) Black")
    (property "ki_keywords" "SMT, PCIE, CONNECTOR")
    (attr smd)
    (fp_text reference "J2" (at 25.543 -1.208 180) (layer "F.SilkS")
        (effects (font (size 0.7 0.7) (thickness 0.15)) (justify left bottom))
    )
    (fp_text value "PCIe_x4_Conn_EdgeMount_Open" (at -5.7 -6.75) (layer "F.Fab")
        (effects (font (size 0.7 0.7) (thickness 0.15)) (justify left bottom))
    )
    (fp_text user "B32" (at 5.985 0.951 90) (layer "B.SilkS") hide
        (effects (font (size 0.7 0.7) (thickness 0.15)) (justify left bottom mirror))
    )
    (fp_text user "B1" (at -3.159 2.983 90) (layer "B.SilkS") hide
        (effects (font (size 0.7 0.7) (thickness 0.15)) (justify left bottom mirror))
    )
    (fp_text user "A32" (at 16.899 -5.8 90) (layer "F.SilkS") hide
        (effects (font (size 0.7 0.7) (thickness 0.15)) (justify left bottom))
    )
    (fp_text user "A1" (at -2.778 -5.78 90) (layer "F.SilkS") hide
        (effects (font (size 0.7 0.7) (thickness 0.15)) (justify left bottom))
    )
    (fp_text user "${REFERENCE}" (at -1.05 -7.95) (layer "F.Fab")
        (effects (font (size 0.7 0.7) (thickness 0.15)) (justify left bottom))
    )
    (fp_text user "License: Apache-2.0" (at -25.401 12.249) (layer "F.Fab") hide
        (effects (font (size 0.7 0.7) (thickness 0.15)) (justify left bottom))
    )
    (fp_text user "Author: Antmicro" (at -25.401 14.649) (layer "F.Fab") hide
        (effects (font (size 0.7 0.7) (thickness 0.15)) (justify left bottom))
    )
    (fp_line (start -24.45 -7.1) (end -24.45 -0.9)
      (stroke (width 0.12) (type solid)) (layer "B.SilkS"))
    (fp_line (start -24.45 -7.1) (end -17.9 -7.1)
      (stroke (width 0.12) (type solid)) (layer "B.SilkS"))
    (fp_line (start 24.44 -7.1) (end 17.89 -7.1)
      (stroke (width 0.12) (type solid)) (layer "B.SilkS"))
    (fp_line (start 24.44 -7.1) (end 24.44 -0.9)
      (stroke (width 0.12) (type solid)) (layer "B.SilkS"))
    (fp_circle (center -16.5 -5.8) (end -16.45 -5.8)
      (stroke (width 0.15) (type solid)) (fill solid) (layer "B.SilkS"))
    (fp_line (start -24.45 -7.1) (end -24.45 -0.9)
      (stroke (width 0.12) (type solid)) (layer "F.SilkS"))
    (fp_line (start -24.45 -7.1) (end -17.9 -7.1)
      (stroke (width 0.12) (type solid)) (layer "F.SilkS"))
    (fp_line (start 24.44 -7.1) (end 17.89 -7.1)
      (stroke (width 0.12) (type solid)) (layer "F.SilkS"))
    (fp_line (start 24.44 -7.1) (end 24.44 -0.9)
      (stroke (width 0.12) (type solid)) (layer "F.SilkS"))
    (fp_circle (center -16.5 -5.8) (end -16.45 -5.8)
      (stroke (width 0.15) (type solid)) (fill solid) (layer "F.SilkS"))
    (fp_rect (start -25.401 -10.25) (end 25.399 10.249)
      (stroke (width 0.05) (type solid)) (fill none) (layer "B.CrtYd"))
    (fp_rect (start -25.401 -10.25) (end 25.399 10.249)
      (stroke (width 0.05) (type solid)) (fill none) (layer "F.CrtYd"))
    (fp_line (start -24.401 -8.35) (end -23.5 -9.25)
      (stroke (width 0.15) (type solid)) (layer "F.Fab"))
    (fp_rect (start -24.401 -9.25) (end 24.399 9.249)
      (stroke (width 0.15) (type solid)) (fill none) (layer "F.Fab"))
    (pad "" np_thru_hole circle (at -21.299 -3.274) (size 2 2) (drill 2) (layers "F&B.Cu" "*.Mask"))
    (pad "" np_thru_hole circle (at 21.301 -3.274) (size 2 2) (drill 2) (layers "F&B.Cu" "*.Mask"))
    (pad "A1" smd rect (at -16.5 -3.326) (size 0.7 4.2) (layers "F.Cu" "F.Paste" "F.Mask")
      (net 124 "unconnected-(J2-PRSNT#1-PadA1)") (pinfunction "PRSNT#1") (pintype "passive+no_connect"))
    (pad "A2" smd rect (at -15.5 -3.326) (size 0.7 4.2) (layers "F.Cu" "F.Paste" "F.Mask")
      (net 8 "12V0_PCIE") (pinfunction "+12V") (pintype "passive"))
    (pad "A3" smd rect (at -14.5 -3.326) (size 0.7 4.2) (layers "F.Cu" "F.Paste" "F.Mask")
      (net 8 "12V0_PCIE") (pinfunction "+12V") (pintype "passive"))
    (pad "A4" smd rect (at -13.5 -3.326) (size 0.7 4.2) (layers "F.Cu" "F.Paste" "F.Mask")
      (net 1 "GND") (pinfunction "GND") (pintype "passive"))
    (pad "A5" smd rect (at -12.5 -3.326) (size 0.7 4.2) (layers "F.Cu" "F.Paste" "F.Mask")
      (net 125 "unconnected-(J2-JTAG2-PadA5)") (pinfunction "JTAG2") (pintype "passive+no_connect"))
    (pad "A6" smd rect (at -11.5 -3.326) (size 0.7 4.2) (layers "F.Cu" "F.Paste" "F.Mask")
      (net 126 "unconnected-(J2-JTAG3-PadA6)") (pinfunction "JTAG3") (pintype "passive+no_connect"))
    (pad "A7" smd rect (at -10.5 -3.326) (size 0.7 4.2) (layers "F.Cu" "F.Paste" "F.Mask")
      (net 127 "unconnected-(J2-JTAG4-PadA7)") (pinfunction "JTAG4") (pintype "passive+no_connect"))
    (pad "A8" smd rect (at -9.5 -3.326) (size 0.7 4.2) (layers "F.Cu" "F.Paste" "F.Mask")
      (net 128 "unconnected-(J2-JTAG5-PadA8)") (pinfunction "JTAG5") (pintype "passive+no_connect"))
    (pad "A9" smd rect (at -8.5 -3.326) (size 0.7 4.2) (layers "F.Cu" "F.Paste" "F.Mask")
      (net 2 "3V3_SYS") (pinfunction "+3V3") (pintype "passive"))
    (pad "A10" smd rect (at -7.5 -3.326) (size 0.7 4.2) (layers "F.Cu" "F.Paste" "F.Mask")
      (net 2 "3V3_SYS") (pinfunction "+3V3") (pintype "passive"))
    (pad "A11" smd rect (at -6.5 -3.326) (size 0.7 4.2) (layers "F.Cu" "F.Paste" "F.Mask")
      (net 43 "PCIE_PWRGD") (pinfunction "PWRGD") (pintype "passive"))
    (pad "A12" smd rect (at -3.5 -3.326) (size 0.7 4.2) (layers "F.Cu" "F.Paste" "F.Mask")
      (net 1 "GND") (pinfunction "GND") (pintype "passive"))
    (pad "A13" smd rect (at -2.5 -3.326) (size 0.7 4.2) (layers "F.Cu" "F.Paste" "F.Mask")
      (net 44 "PCIE_CLK_CON_P") (pinfunction "REFCLK+") (pintype "passive"))
    (pad "A14" smd rect (at -1.5 -3.326) (size 0.7 4.2) (layers "F.Cu" "F.Paste" "F.Mask")
      (net 45 "PCIE_CLK_CON_N") (pinfunction "REFCLK-") (pintype "passive"))
    (pad "A15" smd rect (at -0.5 -3.326) (size 0.7 4.2) (layers "F.Cu" "F.Paste" "F.Mask")
      (net 1 "GND") (pinfunction "GND") (pintype "passive"))
    (pad "A16" smd rect (at 0.496 -3.326) (size 0.7 4.2) (layers "F.Cu" "F.Paste" "F.Mask")
      (net 46 "PCIE_RX0_P") (pinfunction "HSIp(0)") (pintype "passive"))
    (pad "A17" smd rect (at 1.499 -3.326) (size 0.7 4.2) (layers "F.Cu" "F.Paste" "F.Mask")
      (net 47 "PCIE_RX0_N") (pinfunction "HSIn(0)") (pintype "passive"))
    (pad "A18" smd rect (at 2.499 -3.326) (size 0.7 4.2) (layers "F.Cu" "F.Paste" "F.Mask")
      (net 1 "GND") (pinfunction "GND") (pintype "passive"))
    (pad "A19" smd rect (at 3.499 -3.326) (size 0.7 4.2) (layers "F.Cu" "F.Paste" "F.Mask")
      (net 129 "unconnected-(J2-RSVD-PadA19)") (pinfunction "RSVD") (pintype "passive+no_connect"))
    (pad "A20" smd rect (at 4.498 -3.326) (size 0.7 4.2) (layers "F.Cu" "F.Paste" "F.Mask")
      (net 1 "GND") (pinfunction "GND") (pintype "passive"))
    (pad "A21" smd rect (at 5.499 -3.326) (size 0.7 4.2) (layers "F.Cu" "F.Paste" "F.Mask")
      (net 48 "PCIE_RX1_P") (pinfunction "HSIp(1)") (pintype "passive"))
    (pad "A22" smd rect (at 6.499 -3.326) (size 0.7 4.2) (layers "F.Cu" "F.Paste" "F.Mask")
      (net 49 "PCIE_RX1_N") (pinfunction "HSIn(1)") (pintype "passive"))
    (pad "A23" smd rect (at 7.499 -3.326) (size 0.7 4.2) (layers "F.Cu" "F.Paste" "F.Mask")
      (net 1 "GND") (pinfunction "GND") (pintype "passive"))
    (pad "A24" smd rect (at 8.499 -3.326) (size 0.7 4.2) (layers "F.Cu" "F.Paste" "F.Mask")
      (net 1 "GND") (pinfunction "GND") (pintype "passive"))
    (pad "A25" smd rect (at 9.499 -3.326) (size 0.7 4.2) (layers "F.Cu" "F.Paste" "F.Mask")
      (net 50 "PCIE_RX2_P") (pinfunction "HSIp(2)") (pintype "passive"))
    (pad "A26" smd rect (at 10.499 -3.326) (size 0.7 4.2) (layers "F.Cu" "F.Paste" "F.Mask")
      (net 51 "PCIE_RX2_N") (pinfunction "HSIn(2)") (pintype "passive"))
    (pad "A27" smd rect (at 11.499 -3.326) (size 0.7 4.2) (layers "F.Cu" "F.Paste" "F.Mask")
      (net 1 "GND") (pinfunction "GND") (pintype "passive"))
    (pad "A28" smd rect (at 12.499 -3.326) (size 0.7 4.2) (layers "F.Cu" "F.Paste" "F.Mask")
      (net 1 "GND") (pinfunction "GND") (pintype "input"))
    (pad "A29" smd rect (at 13.499 -3.326) (size 0.7 4.2) (layers "F.Cu" "F.Paste" "F.Mask")
      (net 52 "PCIE_RX3_P") (pinfunction "HSIp(3)") (pintype "passive"))
    (pad "A30" smd rect (at 14.499 -3.326) (size 0.7 4.2) (layers "F.Cu" "F.Paste" "F.Mask")
      (net 53 "PCIE_RX3_N") (pinfunction "HSIn(3)") (pintype "passive"))
    (pad "A31" smd rect (at 15.499 -3.326) (size 0.7 4.2) (layers "F.Cu" "F.Paste" "F.Mask")
      (net 1 "GND") (pinfunction "GND") (pintype "passive"))
    (pad "A32" smd rect (at 16.498 -3.326) (size 0.7 4.2) (layers "F.Cu" "F.Paste" "F.Mask")
      (net 130 "unconnected-(J2-RSVD-PadA32)") (pinfunction "RSVD") (pintype "passive+no_connect"))
    (pad "B1" smd rect (at -16.5 -3.331) (size 0.7 4.2) (layers "B.Cu" "B.Paste" "B.Mask")
      (net 8 "12V0_PCIE") (pinfunction "+12V") (pintype "passive"))
    (pad "B2" smd rect (at -15.5 -3.331) (size 0.7 4.2) (layers "B.Cu" "B.Paste" "B.Mask")
      (net 8 "12V0_PCIE") (pinfunction "+12V") (pintype "passive"))
    (pad "B3" smd rect (at -14.5 -3.331) (size 0.7 4.2) (layers "B.Cu" "B.Paste" "B.Mask")
      (net 8 "12V0_PCIE") (pinfunction "+12V") (pintype "passive"))
    (pad "B4" smd rect (at -13.5 -3.331) (size 0.7 4.2) (layers "B.Cu" "B.Paste" "B.Mask")
      (net 1 "GND") (pinfunction "GND") (pintype "passive"))
    (pad "B5" smd rect (at -12.5 -3.331) (size 0.7 4.2) (layers "B.Cu" "B.Paste" "B.Mask")
      (net 131 "unconnected-(J2-SMCLK-PadB5)") (pinfunction "SMCLK") (pintype "passive+no_connect"))
    (pad "B6" smd rect (at -11.5 -3.331) (size 0.7 4.2) (layers "B.Cu" "B.Paste" "B.Mask")
      (net 132 "unconnected-(J2-SMDAT-PadB6)") (pinfunction "SMDAT") (pintype "passive+no_connect"))
    (pad "B7" smd rect (at -10.5 -3.331) (size 0.7 4.2) (layers "B.Cu" "B.Paste" "B.Mask")
      (net 1 "GND") (pinfunction "GND") (pintype "passive"))
    (pad "B8" smd rect (at -9.5 -3.331) (size 0.7 4.2) (layers "B.Cu" "B.Paste" "B.Mask")
      (net 2 "3V3_SYS") (pinfunction "+3V3") (pintype "passive"))
    (pad "B9" smd rect (at -8.5 -3.331) (size 0.7 4.2) (layers "B.Cu" "B.Paste" "B.Mask")
      (net 133 "unconnected-(J2-JTAG1-PadB9)") (pinfunction "JTAG1") (pintype "passive+no_connect"))
    (pad "B10" smd rect (at -7.5 -3.331) (size 0.7 4.2) (layers "B.Cu" "B.Paste" "B.Mask")
      (net 2 "3V3_SYS") (pinfunction "+3V3aux") (pintype "passive"))
    (pad "B11" smd rect (at -6.5 -3.331) (size 0.7 4.2) (layers "B.Cu" "B.Paste" "B.Mask")
      (net 54 "PCIE_WAKE") (pinfunction "WAKE#") (pintype "passive"))
    (pad "B12" smd rect (at -3.5 -3.331) (size 0.7 4.2) (layers "B.Cu" "B.Paste" "B.Mask")
      (net 134 "unconnected-(J2-RSVD-PadB12)") (pinfunction "RSVD") (pintype "passive+no_connect"))
    (pad "B13" smd rect (at -2.5 -3.331) (size 0.7 4.2) (layers "B.Cu" "B.Paste" "B.Mask")
      (net 1 "GND") (pinfunction "GND") (pintype "passive"))
    (pad "B14" smd rect (at -1.5 -3.331) (size 0.7 4.2) (layers "B.Cu" "B.Paste" "B.Mask")
      (net 28 "PCIE_TX0_P") (pinfunction "HSOp(0)") (pintype "passive"))
    (pad "B15" smd rect (at -0.5 -3.331) (size 0.7 4.2) (layers "B.Cu" "B.Paste" "B.Mask")
      (net 24 "PCIE_TX0_N") (pinfunction "HSOn(0)") (pintype "passive"))
    (pad "B16" smd rect (at 0.496 -3.331) (size 0.7 4.2) (layers "B.Cu" "B.Paste" "B.Mask")
      (net 1 "GND") (pinfunction "GND") (pintype "passive"))
    (pad "B17" smd rect (at 1.499 -3.331) (size 0.7 4.2) (layers "B.Cu" "B.Paste" "B.Mask")
      (net 135 "unconnected-(J2-PRSNT#2-PadB17)") (pinfunction "PRSNT#2") (pintype "passive+no_connect"))
    (pad "B18" smd rect (at 2.499 -3.331) (size 0.7 4.2) (layers "B.Cu" "B.Paste" "B.Mask")
      (net 1 "GND") (pinfunction "GND") (pintype "passive"))
    (pad "B19" smd rect (at 3.499 -3.331) (size 0.7 4.2) (layers "B.Cu" "B.Paste" "B.Mask")
      (net 29 "PCIE_TX1_P") (pinfunction "HSOp(1)") (pintype "passive"))
    (pad "B20" smd rect (at 4.498 -3.331) (size 0.7 4.2) (layers "B.Cu" "B.Paste" "B.Mask")
      (net 25 "PCIE_TX1_N") (pinfunction "HSOn(1)") (pintype "passive"))
    (pad "B21" smd rect (at 5.499 -3.331) (size 0.7 4.2) (layers "B.Cu" "B.Paste" "B.Mask")
      (net 1 "GND") (pinfunction "GND") (pintype "passive"))
    (pad "B22" smd rect (at 6.499 -3.331) (size 0.7 4.2) (layers "B.Cu" "B.Paste" "B.Mask")
      (net 1 "GND") (pinfunction "GND") (pintype "passive"))
    (pad "B23" smd rect (at 7.499 -3.331) (size 0.7 4.2) (layers "B.Cu" "B.Paste" "B.Mask")
      (net 30 "PCIE_TX2_P") (pinfunction "HSOp(2)") (pintype "passive"))
    (pad "B24" smd rect (at 8.499 -3.331) (size 0.7 4.2) (layers "B.Cu" "B.Paste" "B.Mask")
      (net 26 "PCIE_TX2_N") (pinfunction "HSOn(2)") (pintype "passive"))
    (pad "B25" smd rect (at 9.499 -3.331) (size 0.7 4.2) (layers "B.Cu" "B.Paste" "B.Mask")
      (net 1 "GND") (pinfunction "GND") (pintype "passive"))
    (pad "B26" smd rect (at 10.499 -3.331) (size 0.7 4.2) (layers "B.Cu" "B.Paste" "B.Mask")
      (net 1 "GND") (pinfunction "GND") (pintype "passive"))
    (pad "B27" smd rect (at 11.499 -3.331) (size 0.7 4.2) (layers "B.Cu" "B.Paste" "B.Mask")
      (net 31 "PCIE_TX3_P") (pinfunction "HSOp(3)") (pintype "passive"))
    (pad "B28" smd rect (at 12.499 -3.331) (size 0.7 4.2) (layers "B.Cu" "B.Paste" "B.Mask")
      (net 27 "PCIE_TX3_N") (pinfunction "HSOn(3)") (pintype "passive"))
    (pad "B29" smd rect (at 13.499 -3.331) (size 0.7 4.2) (layers "B.Cu" "B.Paste" "B.Mask")
      (net 1 "GND") (pinfunction "GND") (pintype "passive"))
    (pad "B30" smd rect (at 14.499 -3.331) (size 0.7 4.2) (layers "B.Cu" "B.Paste" "B.Mask")
      (net 136 "unconnected-(J2-RSVD-PadB30)") (pinfunction "RSVD") (pintype "passive+no_connect"))
    (pad "B31" smd rect (at 15.499 -3.331) (size 0.7 4.2) (layers "B.Cu" "B.Paste" "B.Mask")
      (net 137 "unconnected-(J2-PRSNT#2-PadB31)") (pinfunction "PRSNT#2") (pintype "passive+no_connect"))
    (pad "B32" smd rect (at 16.498 -3.331) (size 0.7 4.2) (layers "B.Cu" "B.Paste" "B.Mask")
      (net 1 "GND") (pinfunction "GND") (pintype "passive"))
  )
)
